(kicad_pcb
	(version 20260206)
	(generator "pcbnew")
	(generator_version "10.0")
	(general
		(thickness 1.6)
		(legacy_teardrops no)
	)
	(paper "A4")
	(title_block
		(title "04192023_DAF0TMB3IC0_F0TG_MB_C_brd_V02_OCP.brd")
		(comment 1 "Grand Teton / footprint 2783 of 8354 (U26), pads 2671-2781 of 6102")
	)
	(layers
		(0 "F.Cu" signal "TOP")
		(4 "In1.Cu" signal "GND")
		(6 "In2.Cu" signal "IN1")
		(8 "In3.Cu" signal "GND1")
		(10 "In4.Cu" signal "IN2")
		(12 "In5.Cu" signal "GND2")
		(14 "In6.Cu" signal "IN3")
		(16 "In7.Cu" signal "GND3")
		(18 "In8.Cu" signal "VCC")
		(20 "In9.Cu" signal "VCC1")
		(22 "In10.Cu" signal "GND4")
		(24 "In11.Cu" signal "IN4")
		(26 "In12.Cu" signal "GND5")
		(28 "In13.Cu" signal "IN5")
		(30 "In14.Cu" signal "GND6")
		(32 "In15.Cu" signal "IN6")
		(34 "In16.Cu" signal "GND7")
		(2 "B.Cu" signal "BOTTOM")
		(9 "F.Adhes" user "F.Adhesive")
		(11 "B.Adhes" user "B.Adhesive")
		(13 "F.Paste" user "Package Geometry/Pastemask Top")
		(15 "B.Paste" user "Package Geometry/Pastemask Bottom")
		(5 "F.SilkS" user "Ref Des/Silkscreen Top")
		(7 "B.SilkS" user "Ref Des/Silkscreen Bottom")
		(1 "F.Mask" user "Board Geometry/Soldermask Top")
		(3 "B.Mask" user "Board Geometry/Soldermask Bottom")
		(17 "Dwgs.User" user "User.Drawings")
		(19 "Cmts.User" user "User.Comments")
		(21 "Eco1.User" user "User.Eco1")
		(23 "Eco2.User" user "User.Eco2")
		(25 "Edge.Cuts" user "Board Geometry/Outline")
		(27 "Margin" user)
		(31 "F.CrtYd" user "Package Geometry/Place Bound Top")
		(29 "B.CrtYd" user "Package Geometry/Place Bound Bottom")
		(35 "F.Fab" user "Ref Des/Assembly Top")
		(33 "B.Fab" user "Ref Des/Assembly Bottom")
	)
	(footprint ""
		(layer "F.Cu")
		(at 111.927894 -258.880356 180)
		(property "Reference" "U26"
			(at -45.05579 -61.794136 0)
			(unlocked yes)
			(layer "F.SilkS")
			(effects
				(font
					(size 0.7874 0.5842)
					(thickness 0.1524)
				)
			)
		)
		(property "Value" ""
			(at 0 0 180)
			(layer "F.Fab")
			(effects
				(font
					(size 1.27 1.27)
				)
			)
		)
		(duplicate_pad_numbers_are_jumpers no)
		(pad "BY8" smd circle
			(at -28.349956 13.320014 180)
			(size 0.450088 0.450088)
			(layers "F.Cu" "F.Mask" "F.Paste")
			(net "GND")
		)
		(pad "BY9" smd circle
			(at -27.409902 13.320014 180)
			(size 0.450088 0.450088)
			(layers "F.Cu" "F.Mask" "F.Paste")
			(net "M_L_CPU1_SB_CB<0>")
		)
		(pad "BY10" smd circle
			(at -26.470102 13.320014 180)
			(size 0.450088 0.450088)
			(layers "F.Cu" "F.Mask" "F.Paste")
			(net "GND")
		)
		(pad "BY11" smd circle
			(at -25.530048 13.320014 180)
			(size 0.450088 0.450088)
			(layers "F.Cu" "F.Mask" "F.Paste")
			(net "M_L_CPU1_SB_DQS_DP<4>")
		)
		(pad "BY12" smd circle
			(at -24.589994 13.320014 180)
			(size 0.450088 0.450088)
			(layers "F.Cu" "F.Mask" "F.Paste")
			(net "GND")
		)
		(pad "BY13" smd circle
			(at -23.64994 13.320014 180)
			(size 0.450088 0.450088)
			(layers "F.Cu" "F.Mask" "F.Paste")
			(net "M_H_CPU1_SB_CB<0>")
		)
		(pad "BY14" smd circle
			(at -22.709886 13.320014 180)
			(size 0.450088 0.450088)
			(layers "F.Cu" "F.Mask" "F.Paste")
			(net "M_H_CPU1_SB_DQS_DP<4>")
		)
		(pad "BY15" smd circle
			(at -21.770086 13.320014 180)
			(size 0.450088 0.450088)
			(layers "F.Cu" "F.Mask" "F.Paste")
			(net "GND")
		)
		(pad "BY16" smd circle
			(at -20.830032 13.320014 180)
			(size 0.450088 0.450088)
			(layers "F.Cu" "F.Mask" "F.Paste")
			(net "M_J_CPU1_SB_CB<0>")
		)
		(pad "BY17" smd circle
			(at -19.889978 13.320014 180)
			(size 0.450088 0.450088)
			(layers "F.Cu" "F.Mask" "F.Paste")
			(net "GND")
		)
		(pad "BY18" smd circle
			(at -18.949924 13.320014 180)
			(size 0.450088 0.450088)
			(layers "F.Cu" "F.Mask" "F.Paste")
			(net "M_J_CPU1_SB_DQS_DP<4>")
		)
		(pad "BY19" smd circle
			(at -18.010124 13.320014 180)
			(size 0.450088 0.450088)
			(layers "F.Cu" "F.Mask" "F.Paste")
			(net "GND")
		)
		(pad "BY20" smd circle
			(at -17.07007 13.320014 180)
			(size 0.450088 0.450088)
			(layers "F.Cu" "F.Mask" "F.Paste")
			(net "M_I_CPU1_SB_CB<0>")
		)
		(pad "BY21" smd circle
			(at -16.130016 13.320014 180)
			(size 0.450088 0.450088)
			(layers "F.Cu" "F.Mask" "F.Paste")
			(net "M_I_CPU1_SB_DQS_DP<4>")
		)
		(pad "BY22" smd circle
			(at -15.189962 13.320014 180)
			(size 0.450088 0.450088)
			(layers "F.Cu" "F.Mask" "F.Paste")
			(net "GND")
		)
		(pad "BY23" smd circle
			(at -14.249908 13.320014 180)
			(size 0.450088 0.450088)
			(layers "F.Cu" "F.Mask" "F.Paste")
			(net "PVDDCR_CPU1_P1")
		)
		(pad "BY24" smd circle
			(at -13.310108 13.320014 180)
			(size 0.450088 0.450088)
			(layers "F.Cu" "F.Mask" "F.Paste")
			(net "PVDDCR_CPU1_P1")
		)
		(pad "BY25" smd circle
			(at -12.370054 13.320014 180)
			(size 0.450088 0.450088)
			(layers "F.Cu" "F.Mask" "F.Paste")
			(net "GND")
		)
		(pad "BY26" smd circle
			(at -11.43 13.320014 180)
			(size 0.450088 0.450088)
			(layers "F.Cu" "F.Mask" "F.Paste")
			(net "PVDDCR_CPU1_P1")
		)
		(pad "BY27" smd circle
			(at -10.489946 13.320014 180)
			(size 0.450088 0.450088)
			(layers "F.Cu" "F.Mask" "F.Paste")
			(net "PVDDCR_CPU1_P1")
		)
		(pad "BY28" smd circle
			(at -9.549892 13.320014 180)
			(size 0.450088 0.450088)
			(layers "F.Cu" "F.Mask" "F.Paste")
			(net "GND")
		)
		(pad "BY29" smd circle
			(at -8.610092 13.320014 180)
			(size 0.450088 0.450088)
			(layers "F.Cu" "F.Mask" "F.Paste")
			(net "PVDDCR_CPU1_P1")
		)
		(pad "BY30" smd circle
			(at -7.670038 13.320014 180)
			(size 0.450088 0.450088)
			(layers "F.Cu" "F.Mask" "F.Paste")
			(net "PVDDCR_CPU1_P1")
		)
		(pad "BY31" smd circle
			(at -6.729984 13.320014 180)
			(size 0.450088 0.450088)
			(layers "F.Cu" "F.Mask" "F.Paste")
			(net "GND")
		)
		(pad "BY32" smd circle
			(at -5.78993 13.320014 180)
			(size 0.450088 0.450088)
			(layers "F.Cu" "F.Mask" "F.Paste")
			(net "PVDDCR_CPU1_P1")
		)
		(pad "BY33" smd circle
			(at -4.849876 13.320014 180)
			(size 0.450088 0.450088)
			(layers "F.Cu" "F.Mask" "F.Paste")
			(net "PVDDCR_CPU1_P1")
		)
		(pad "BY34" smd circle
			(at -3.910076 13.320014 180)
			(size 0.450088 0.450088)
			(layers "F.Cu" "F.Mask" "F.Paste")
			(net "GND")
		)
		(pad "BY35" smd circle
			(at -2.970022 13.320014 180)
			(size 0.450088 0.450088)
			(layers "F.Cu" "F.Mask" "F.Paste")
			(net "P5E_CPU1_P2_TX_DN<3>")
		)
		(pad "BY36" smd circle
			(at -2.029968 13.320014 180)
			(size 0.450088 0.450088)
			(layers "F.Cu" "F.Mask" "F.Paste")
			(net "P5E_CPU1_P2_TX_DP<3>")
		)
		(pad "BY37" smd circle
			(at -1.089914 13.320014 180)
			(size 0.450088 0.450088)
			(layers "F.Cu" "F.Mask" "F.Paste")
			(net "GND")
		)
		(pad "BY39" smd circle
			(at 0.78994 13.320014 180)
			(size 0.450088 0.450088)
			(layers "F.Cu" "F.Mask" "F.Paste")
			(net "GND")
		)
		(pad "BY40" smd circle
			(at 1.729994 13.320014 180)
			(size 0.450088 0.450088)
			(layers "F.Cu" "F.Mask" "F.Paste")
			(net "P5E_CPU1_P0_RX_DP<12>")
		)
		(pad "BY41" smd circle
			(at 2.670048 13.320014 180)
			(size 0.450088 0.450088)
			(layers "F.Cu" "F.Mask" "F.Paste")
			(net "P5E_CPU1_P0_RX_DN<12>")
		)
		(pad "BY42" smd circle
			(at 3.610102 13.320014 180)
			(size 0.450088 0.450088)
			(layers "F.Cu" "F.Mask" "F.Paste")
			(net "GND")
		)
		(pad "BY43" smd circle
			(at 4.549902 13.320014 180)
			(size 0.450088 0.450088)
			(layers "F.Cu" "F.Mask" "F.Paste")
			(net "PVDDCR_CPU1_P1")
		)
		(pad "BY44" smd circle
			(at 5.489956 13.320014 180)
			(size 0.450088 0.450088)
			(layers "F.Cu" "F.Mask" "F.Paste")
			(net "PVDDCR_CPU1_P1")
		)
		(pad "BY45" smd circle
			(at 6.43001 13.320014 180)
			(size 0.450088 0.450088)
			(layers "F.Cu" "F.Mask" "F.Paste")
			(net "GND")
		)
		(pad "BY46" smd circle
			(at 7.370064 13.320014 180)
			(size 0.450088 0.450088)
			(layers "F.Cu" "F.Mask" "F.Paste")
			(net "PVDDCR_CPU1_P1")
		)
		(pad "BY47" smd circle
			(at 8.310118 13.320014 180)
			(size 0.450088 0.450088)
			(layers "F.Cu" "F.Mask" "F.Paste")
			(net "PVDDCR_CPU1_P1")
		)
		(pad "BY48" smd circle
			(at 9.249918 13.320014 180)
			(size 0.450088 0.450088)
			(layers "F.Cu" "F.Mask" "F.Paste")
			(net "GND")
		)
		(pad "BY49" smd circle
			(at 10.189972 13.320014 180)
			(size 0.450088 0.450088)
			(layers "F.Cu" "F.Mask" "F.Paste")
			(net "PVDDCR_CPU1_P1")
		)
		(pad "BY50" smd circle
			(at 11.130026 13.320014 180)
			(size 0.450088 0.450088)
			(layers "F.Cu" "F.Mask" "F.Paste")
			(net "PVDDCR_CPU1_P1")
		)
		(pad "BY51" smd circle
			(at 12.07008 13.320014 180)
			(size 0.450088 0.450088)
			(layers "F.Cu" "F.Mask" "F.Paste")
			(net "GND")
		)
		(pad "BY52" smd circle
			(at 13.00988 13.320014 180)
			(size 0.450088 0.450088)
			(layers "F.Cu" "F.Mask" "F.Paste")
			(net "PVDDCR_CPU1_P1")
		)
		(pad "BY53" smd circle
			(at 13.949934 13.320014 180)
			(size 0.450088 0.450088)
			(layers "F.Cu" "F.Mask" "F.Paste")
			(net "PVDDCR_CPU1_P1")
		)
		(pad "BY54" smd circle
			(at 14.889988 13.320014 180)
			(size 0.450088 0.450088)
			(layers "F.Cu" "F.Mask" "F.Paste")
			(net "GND")
		)
		(pad "BY55" smd circle
			(at 15.830042 13.320014 180)
			(size 0.450088 0.450088)
			(layers "F.Cu" "F.Mask" "F.Paste")
			(net "M_C_CPU1_SB_DQS_DP<4>")
		)
		(pad "BY56" smd circle
			(at 16.770096 13.320014 180)
			(size 0.450088 0.450088)
			(layers "F.Cu" "F.Mask" "F.Paste")
			(net "M_C_CPU1_SB_CB<0>")
		)
		(pad "BY57" smd circle
			(at 17.709896 13.320014 180)
			(size 0.450088 0.450088)
			(layers "F.Cu" "F.Mask" "F.Paste")
			(net "GND")
		)
		(pad "BY58" smd circle
			(at 18.64995 13.320014 180)
			(size 0.450088 0.450088)
			(layers "F.Cu" "F.Mask" "F.Paste")
			(net "M_D_CPU1_SB_DQS_DP<4>")
		)
		(pad "BY59" smd circle
			(at 19.590004 13.320014 180)
			(size 0.450088 0.450088)
			(layers "F.Cu" "F.Mask" "F.Paste")
			(net "GND")
		)
		(pad "BY60" smd circle
			(at 20.530058 13.320014 180)
			(size 0.450088 0.450088)
			(layers "F.Cu" "F.Mask" "F.Paste")
			(net "M_D_CPU1_SB_CB<0>")
		)
		(pad "BY61" smd circle
			(at 21.470112 13.320014 180)
			(size 0.450088 0.450088)
			(layers "F.Cu" "F.Mask" "F.Paste")
			(net "GND")
		)
		(pad "BY62" smd circle
			(at 22.409912 13.320014 180)
			(size 0.450088 0.450088)
			(layers "F.Cu" "F.Mask" "F.Paste")
			(net "M_B_CPU1_SB_DQS_DP<4>")
		)
		(pad "BY63" smd circle
			(at 23.349966 13.320014 180)
			(size 0.450088 0.450088)
			(layers "F.Cu" "F.Mask" "F.Paste")
			(net "M_B_CPU1_SB_CB<0>")
		)
		(pad "BY64" smd circle
			(at 24.29002 13.320014 180)
			(size 0.450088 0.450088)
			(layers "F.Cu" "F.Mask" "F.Paste")
			(net "GND")
		)
		(pad "BY65" smd circle
			(at 25.230074 13.320014 180)
			(size 0.450088 0.450088)
			(layers "F.Cu" "F.Mask" "F.Paste")
			(net "M_F_CPU1_SB_DQS_DP<4>")
		)
		(pad "BY66" smd circle
			(at 26.170128 13.320014 180)
			(size 0.450088 0.450088)
			(layers "F.Cu" "F.Mask" "F.Paste")
			(net "GND")
		)
		(pad "BY67" smd circle
			(at 27.109928 13.320014 180)
			(size 0.450088 0.450088)
			(layers "F.Cu" "F.Mask" "F.Paste")
			(net "M_F_CPU1_SB_CB<0>")
		)
		(pad "BY68" smd circle
			(at 28.049982 13.320014 180)
			(size 0.450088 0.450088)
			(layers "F.Cu" "F.Mask" "F.Paste")
			(net "GND")
		)
		(pad "BY69" smd circle
			(at 28.990036 13.320014 180)
			(size 0.450088 0.450088)
			(layers "F.Cu" "F.Mask" "F.Paste")
			(net "M_E_CPU1_SB_DQS_DP<4>")
		)
		(pad "BY70" smd circle
			(at 29.93009 13.320014 180)
			(size 0.450088 0.450088)
			(layers "F.Cu" "F.Mask" "F.Paste")
			(net "M_E_CPU1_SB_CB<0>")
		)
		(pad "BY71" smd circle
			(at 30.86989 13.320014 180)
			(size 0.450088 0.450088)
			(layers "F.Cu" "F.Mask" "F.Paste")
			(net "GND")
		)
		(pad "BY72" smd circle
			(at 31.809944 13.320014 180)
			(size 0.450088 0.450088)
			(layers "F.Cu" "F.Mask" "F.Paste")
			(net "M_A_CPU1_SB_DQS_DP<4>")
		)
		(pad "BY73" smd circle
			(at 32.749998 13.320014 180)
			(size 0.450088 0.450088)
			(layers "F.Cu" "F.Mask" "F.Paste")
			(net "GND")
		)
		(pad "BY74" smd circle
			(at 33.690052 13.320014 180)
			(size 0.450088 0.450088)
			(layers "F.Cu" "F.Mask" "F.Paste")
			(net "M_A_CPU1_SB_CB<0>")
		)
		(pad "C1" smd circle
			(at -34.159952 -35.189922 180)
			(size 0.450088 0.450088)
			(layers "F.Cu" "F.Mask" "F.Paste")
			(net "GND")
		)
		(pad "C2" smd circle
			(at -33.219898 -35.189922 180)
			(size 0.450088 0.450088)
			(layers "F.Cu" "F.Mask" "F.Paste")
			(net "VSENSE_PVDDCR_CPU0_P1_DP")
		)
		(pad "C3" smd circle
			(at -32.280098 -35.189922 180)
			(size 0.450088 0.450088)
			(layers "F.Cu" "F.Mask" "F.Paste")
			(net "VSENSE_VSS_SENSE_A_P1")
		)
		(pad "C4" smd circle
			(at -31.340044 -35.189922 180)
			(size 0.450088 0.450088)
			(layers "F.Cu" "F.Mask" "F.Paste")
			(net "PVDDCR_SOC_P1")
		)
		(pad "C5" smd circle
			(at -30.39999 -35.189922 180)
			(size 0.450088 0.450088)
			(layers "F.Cu" "F.Mask" "F.Paste")
			(net "GND")
		)
		(pad "C6" smd circle
			(at -29.459936 -35.189922 180)
			(size 0.450088 0.450088)
			(layers "F.Cu" "F.Mask" "F.Paste")
			(net "CLK_100M_CPU1_CLK02_R_DN")
		)
		(pad "C7" smd circle
			(at -28.519882 -35.189922 180)
			(size 0.450088 0.450088)
			(layers "F.Cu" "F.Mask" "F.Paste")
			(net "I3C_1_SPD_DDRGL_CPU1_R_SCL")
		)
		(pad "C8" smd circle
			(at -27.580082 -35.189922 180)
			(size 0.450088 0.450088)
			(layers "F.Cu" "F.Mask" "F.Paste")
			(net "GND")
		)
		(pad "C9" smd circle
			(at -26.640028 -35.189922 180)
			(size 0.450088 0.450088)
			(layers "F.Cu" "F.Mask" "F.Paste")
			(net "CLK_100M_CPU1_CLK05_R_DN")
		)
		(pad "C10" smd circle
			(at -25.699974 -35.189922 180)
			(size 0.450088 0.450088)
			(layers "F.Cu" "F.Mask" "F.Paste")
			(net "GND")
		)
		(pad "C11" smd circle
			(at -24.75992 -35.189922 180)
			(size 0.450088 0.450088)
			(layers "F.Cu" "F.Mask" "F.Paste")
			(net "GND")
		)
		(pad "C12" smd circle
			(at -23.82012 -35.189922 180)
			(size 0.450088 0.450088)
			(layers "F.Cu" "F.Mask" "F.Paste")
			(net "CLK_100M_CPU1_CLK04_R_DN")
		)
		(pad "C13" smd circle
			(at -22.880066 -35.189922 180)
			(size 0.450088 0.450088)
			(layers "F.Cu" "F.Mask" "F.Paste")
			(net "GND")
		)
		(pad "C14" smd circle
			(at -21.940012 -35.189922 180)
			(size 0.450088 0.450088)
			(layers "F.Cu" "F.Mask" "F.Paste")
			(net "Net_2081")
		)
		(pad "C15" smd circle
			(at -20.999958 -35.189922 180)
			(size 0.450088 0.450088)
			(layers "F.Cu" "F.Mask" "F.Paste")
			(net "GND")
		)
		(pad "C16" smd circle
			(at -20.059904 -35.189922 180)
			(size 0.450088 0.450088)
			(layers "F.Cu" "F.Mask" "F.Paste")
			(net "JTAG_CPU1_DBREQ_N")
		)
		(pad "C17" smd circle
			(at -19.120104 -35.189922 180)
			(size 0.450088 0.450088)
			(layers "F.Cu" "F.Mask" "F.Paste")
			(net "JTAG_CPU1_TDI")
		)
		(pad "C18" smd circle
			(at -18.18005 -35.189922 180)
			(size 0.450088 0.450088)
			(layers "F.Cu" "F.Mask" "F.Paste")
			(net "JTAG_CPU1_R_TDO")
		)
		(pad "C19" smd circle
			(at -17.239996 -35.189922 180)
			(size 0.450088 0.450088)
			(layers "F.Cu" "F.Mask" "F.Paste")
			(net "CPU1_SP5R1")
		)
		(pad "C20" smd circle
			(at -16.299942 -35.189922 180)
			(size 0.450088 0.450088)
			(layers "F.Cu" "F.Mask" "F.Paste")
			(net "PVDDCR_CPU0_P1")
		)
		(pad "C21" smd circle
			(at -15.359888 -35.189922 180)
			(size 0.450088 0.450088)
			(layers "F.Cu" "F.Mask" "F.Paste")
			(net "GND")
		)
		(pad "C22" smd circle
			(at -14.420088 -35.189922 180)
			(size 0.450088 0.450088)
			(layers "F.Cu" "F.Mask" "F.Paste")
			(net "FM_P1_PCC0_N")
		)
		(pad "C23" smd circle
			(at -13.480034 -35.189922 180)
			(size 0.450088 0.450088)
			(layers "F.Cu" "F.Mask" "F.Paste")
			(net "Net_2172")
		)
		(pad "C24" smd circle
			(at -12.53998 -35.189922 180)
			(size 0.450088 0.450088)
			(layers "F.Cu" "F.Mask" "F.Paste")
			(net "GND")
		)
		(pad "C25" smd circle
			(at -11.599926 -35.189922 180)
			(size 0.450088 0.450088)
			(layers "F.Cu" "F.Mask" "F.Paste")
			(net "NC_CPU1_USB3_USB00_TXN")
		)
		(pad "C26" smd circle
			(at -10.659872 -35.189922 180)
			(size 0.450088 0.450088)
			(layers "F.Cu" "F.Mask" "F.Paste")
			(net "NC_CPU1_USB3_USB00_TXP")
		)
		(pad "C27" smd circle
			(at -9.720072 -35.189922 180)
			(size 0.450088 0.450088)
			(layers "F.Cu" "F.Mask" "F.Paste")
			(net "GND")
		)
		(pad "C28" smd circle
			(at -8.780018 -35.189922 180)
			(size 0.450088 0.450088)
			(layers "F.Cu" "F.Mask" "F.Paste")
			(net "NC_CPU1_USB3_USB01_RXN")
		)
		(pad "C29" smd circle
			(at -7.839964 -35.189922 180)
			(size 0.450088 0.450088)
			(layers "F.Cu" "F.Mask" "F.Paste")
			(net "NC_CPU1_USB3_USB01_RXP")
		)
		(pad "C30" smd circle
			(at -6.89991 -35.189922 180)
			(size 0.450088 0.450088)
			(layers "F.Cu" "F.Mask" "F.Paste")
			(net "GND")
		)
		(pad "C31" smd circle
			(at -5.96011 -35.189922 180)
			(size 0.450088 0.450088)
			(layers "F.Cu" "F.Mask" "F.Paste")
			(net "Net_2148")
		)
		(pad "C32" smd circle
			(at -5.020056 -35.189922 180)
			(size 0.450088 0.450088)
			(layers "F.Cu" "F.Mask" "F.Paste")
			(net "NC_CPU1_AZ_BITCLK")
		)
		(pad "C33" smd circle
			(at -4.080002 -35.189922 180)
			(size 0.450088 0.450088)
			(layers "F.Cu" "F.Mask" "F.Paste")
			(net "NC_CPU1_AZ_SDIN0")
		)
		(pad "C34" smd circle
			(at -3.139948 -35.189922 180)
			(size 0.450088 0.450088)
			(layers "F.Cu" "F.Mask" "F.Paste")
			(net "Net_2149")
		)
		(pad "C35" smd circle
			(at -2.199894 -35.189922 180)
			(size 0.450088 0.450088)
			(layers "F.Cu" "F.Mask" "F.Paste")
			(net "Net_2150")
		)
		(pad "C36" smd circle
			(at -1.260094 -35.189922 180)
			(size 0.450088 0.450088)
			(layers "F.Cu" "F.Mask" "F.Paste")
			(net "GND")
		)
		(pad "C40" smd circle
			(at 1.560068 -35.189922 180)
			(size 0.450088 0.450088)
			(layers "F.Cu" "F.Mask" "F.Paste")
			(net "GND")
		)
		(pad "C41" smd circle
			(at 2.500122 -35.189922 180)
			(size 0.450088 0.450088)
			(layers "F.Cu" "F.Mask" "F.Paste")
			(net "P3E_CPU1_P5_TX_DP<1>")
		)
		(pad "C42" smd circle
			(at 3.439922 -35.189922 180)
			(size 0.450088 0.450088)
			(layers "F.Cu" "F.Mask" "F.Paste")
			(net "P3E_CPU1_P5_TX_DN<1>")
		)
		(pad "C43" smd circle
			(at 4.379976 -35.189922 180)
			(size 0.450088 0.450088)
			(layers "F.Cu" "F.Mask" "F.Paste")
			(net "GND")
		)
		(pad "C44" smd circle
			(at 5.32003 -35.189922 180)
			(size 0.450088 0.450088)
			(layers "F.Cu" "F.Mask" "F.Paste")
			(net "P3E_CPU1_P5_TX_DP<0>")
		)
		(pad "C45" smd circle
			(at 6.260084 -35.189922 180)
			(size 0.450088 0.450088)
			(layers "F.Cu" "F.Mask" "F.Paste")
			(net "P3E_CPU1_P5_TX_DN<0>")
		)
		(pad "C46" smd circle
			(at 7.199884 -35.189922 180)
			(size 0.450088 0.450088)
			(layers "F.Cu" "F.Mask" "F.Paste")
			(net "GND")
		)
		(pad "C47" smd circle
			(at 8.139938 -35.189922 180)
			(size 0.450088 0.450088)
			(layers "F.Cu" "F.Mask" "F.Paste")
			(net "WAFL_CPU1_TX1_CPU0_RX0_DP")
		)
		(pad "C48" smd circle
			(at 9.079992 -35.189922 180)
			(size 0.450088 0.450088)
			(layers "F.Cu" "F.Mask" "F.Paste")
			(net "WAFL_CPU1_TX1_CPU0_RX0_DN")
		)
	)
)
